(kicad_pcb
	(version 20260206)
	(generator "pcbnew")
	(generator_version "10.0")
	(general
		(thickness 1.6)
		(legacy_teardrops no)
	)
	(paper "A4")
	(title_block
		(title "03242023_DA0F0TMBIJ0_F0T_Motherboard_J_brd_V01_OCP.brd")
		(comment 1 "Grand Teton / footprints 593-598 of 6105")
	)
	(layers
		(0 "F.Cu" signal "TOP")
		(4 "In1.Cu" signal "GND")
		(6 "In2.Cu" signal "IN1")
		(8 "In3.Cu" signal "GND1")
		(10 "In4.Cu" signal "IN2")
		(12 "In5.Cu" signal "GND2")
		(14 "In6.Cu" signal "IN3")
		(16 "In7.Cu" signal "GND3")
		(18 "In8.Cu" signal "VCC")
		(20 "In9.Cu" signal "VCC1")
		(22 "In10.Cu" signal "GND4")
		(24 "In11.Cu" signal "IN4")
		(26 "In12.Cu" signal "GND5")
		(28 "In13.Cu" signal "IN5")
		(30 "In14.Cu" signal "GND6")
		(32 "In15.Cu" signal "IN6")
		(34 "In16.Cu" signal "GND7")
		(2 "B.Cu" signal "BOTTOM")
		(9 "F.Adhes" user "F.Adhesive")
		(11 "B.Adhes" user "B.Adhesive")
		(13 "F.Paste" user "Package Geometry/Pastemask Top")
		(15 "B.Paste" user "Package Geometry/Pastemask Bottom")
		(5 "F.SilkS" user "Ref Des/Silkscreen Top")
		(7 "B.SilkS" user "Ref Des/Silkscreen Bottom")
		(1 "F.Mask" user "Board Geometry/Soldermask Top")
		(3 "B.Mask" user "Board Geometry/Soldermask Bottom")
		(17 "Dwgs.User" user "User.Drawings")
		(19 "Cmts.User" user "User.Comments")
		(21 "Eco1.User" user "User.Eco1")
		(23 "Eco2.User" user "User.Eco2")
		(25 "Edge.Cuts" user "Board Geometry/Outline")
		(27 "Margin" user)
		(31 "F.CrtYd" user "Package Geometry/Place Bound Top")
		(29 "B.CrtYd" user "Package Geometry/Place Bound Bottom")
		(35 "F.Fab" user "Ref Des/Assembly Top")
		(33 "B.Fab" user "Ref Des/Assembly Bottom")
	)
	(footprint ""
		(layer "F.Cu")
		(at 120.269 -62.575948 90)
		(property "Reference" "JP16"
			(at -0.02667 6.985 0)
			(unlocked yes)
			(layer "F.SilkS")
			(effects
				(font
					(size 0.7874 0.5842)
					(thickness 0.1524)
				)
				(justify left)
			)
		)
		(property "Value" ""
			(at 0 0 90)
			(layer "F.Fab")
			(effects
				(font
					(size 1.27 1.27)
				)
			)
		)
		(duplicate_pad_numbers_are_jumpers no)
		(fp_line
			(start 1.249934 -1.320038)
			(end 1.249934 6.400038)
			(stroke
				(width 0.1524)
				(type default)
			)
			(layer "F.SilkS")
		)
		(fp_line
			(start -1.249934 -1.320038)
			(end 1.249934 -1.320038)
			(stroke
				(width 0.1524)
				(type default)
			)
			(layer "F.SilkS")
		)
		(fp_line
			(start 1.249934 6.400038)
			(end -1.249934 6.400038)
			(stroke
				(width 0.1524)
				(type default)
			)
			(layer "F.SilkS")
		)
		(fp_line
			(start -1.249934 6.400038)
			(end -1.249934 -1.320038)
			(stroke
				(width 0.1524)
				(type default)
			)
			(layer "F.SilkS")
		)
		(fp_poly
			(pts
				(xy -2.156206 -2.266442) (xy -1.72339 -1.09982) (xy -2.916428 -1.453642)
			)
			(stroke
				(width 0)
				(type default)
			)
			(fill yes)
			(layer "F.SilkS")
		)
		(fp_line
			(start 1.249934 -1.320038)
			(end 1.249934 6.400038)
			(stroke
				(width 0.1)
				(type default)
			)
			(layer "F.Fab")
		)
		(fp_line
			(start -1.249934 -1.320038)
			(end 1.249934 -1.320038)
			(stroke
				(width 0.1)
				(type default)
			)
			(layer "F.Fab")
		)
		(fp_line
			(start 1.249934 6.400038)
			(end -1.249934 6.400038)
			(stroke
				(width 0.1)
				(type default)
			)
			(layer "F.Fab")
		)
		(fp_line
			(start -1.249934 6.400038)
			(end -1.249934 -1.320038)
			(stroke
				(width 0.1)
				(type default)
			)
			(layer "F.Fab")
		)
		(fp_poly
			(pts
				(xy -2.5654 -0.556514) (xy -1.452372 0) (xy -2.5654 0.556514)
			)
			(stroke
				(width 0)
				(type default)
			)
			(fill yes)
			(layer "F.Fab")
		)
		(fp_text user "3"
			(at -1.778 5.13207 90)
			(unlocked yes)
			(layer "F.SilkS")
			(effects
				(font
					(size 0.7874 0.5842)
					(thickness 0.1524)
				)
			)
		)
		(fp_text user "1"
			(at -1.143 0.02667 90)
			(unlocked yes)
			(layer "B.SilkS")
			(effects
				(font
					(size 0.7874 0.5842)
					(thickness 0.1524)
				)
				(justify mirror)
			)
		)
		(fp_text user "3"
			(at -1.1557 5.18287 90)
			(unlocked yes)
			(layer "B.SilkS")
			(effects
				(font
					(size 0.7874 0.5842)
					(thickness 0.1524)
				)
				(justify mirror)
			)
		)
		(fp_text user "1"
			(at -1.143 0.02667 90)
			(unlocked yes)
			(layer "B.Fab")
			(effects
				(font
					(size 0.7874 0.5842)
					(thickness 0.1524)
				)
				(justify mirror)
			)
		)
		(fp_text user "3"
			(at -1.1557 5.18287 90)
			(unlocked yes)
			(layer "B.Fab")
			(effects
				(font
					(size 0.7874 0.5842)
					(thickness 0.1524)
				)
				(justify mirror)
			)
		)
		(fp_text user "3"
			(at -1.778 5.13207 90)
			(unlocked yes)
			(layer "F.Fab")
			(effects
				(font
					(size 0.7874 0.5842)
					(thickness 0.1524)
				)
			)
		)
		(pad "1" thru_hole rect
			(at 0 0 90)
			(size 1.5494 1.5494)
			(drill 1.0414)
			(layers "*.Cu" "*.Mask")
			(remove_unused_layers no)
			(net "PU_JTAG_SW_PU")
			(clearance 0)
			(padstack
				(mode front_inner_back)
				(layer "Inner"
					(shape circle)
					(size 1.5494 1.5494)
					(clearance 0)
				)
				(layer "B.Cu"
					(shape rect)
					(size 1.5494 1.5494)
					(clearance 0)
				)
			)
		)
		(pad "2" thru_hole circle
			(at 0 2.54 90)
			(size 1.5494 1.5494)
			(drill 1.0414)
			(layers "*.Cu" "*.Mask")
			(remove_unused_layers no)
			(net "JTAG_BMC_SW_OE")
			(clearance 0)
		)
		(pad "3" thru_hole circle
			(at 0 5.08 90)
			(size 1.5494 1.5494)
			(drill 1.0414)
			(layers "*.Cu" "*.Mask")
			(remove_unused_layers no)
			(net "GND")
			(clearance 0)
		)
	)
	(footprint ""
		(layer "F.Cu")
		(at 102.84841 -55.277004)
		(property "Reference" "U86"
			(at -2.032 -3.27533 0)
			(unlocked yes)
			(layer "F.SilkS")
			(effects
				(font
					(size 0.7874 0.5842)
					(thickness 0.1524)
				)
				(justify left)
			)
		)
		(property "Value" ""
			(at 0 0 0)
			(layer "F.Fab")
			(effects
				(font
					(size 1.27 1.27)
				)
			)
		)
		(duplicate_pad_numbers_are_jumpers no)
		(fp_line
			(start -2.0066 -2.5527)
			(end -0.5715 -2.5527)
			(stroke
				(width 0.1524)
				(type default)
			)
			(layer "F.SilkS")
		)
		(fp_line
			(start -2.0066 2.5527)
			(end -2.0066 -2.5527)
			(stroke
				(width 0.1524)
				(type default)
			)
			(layer "F.SilkS")
		)
		(fp_line
			(start -0.5715 -2.5527)
			(end 0 -1.9812)
			(stroke
				(width 0.1524)
				(type default)
			)
			(layer "F.SilkS")
		)
		(fp_line
			(start 0 -1.9812)
			(end 0.5715 -2.5527)
			(stroke
				(width 0.1524)
				(type default)
			)
			(layer "F.SilkS")
		)
		(fp_line
			(start 0.5715 -2.5527)
			(end 2.0066 -2.5527)
			(stroke
				(width 0.1524)
				(type default)
			)
			(layer "F.SilkS")
		)
		(fp_line
			(start 2.0066 -2.5527)
			(end 2.0066 2.5527)
			(stroke
				(width 0.1524)
				(type default)
			)
			(layer "F.SilkS")
		)
		(fp_line
			(start 2.0066 2.5527)
			(end -2.0066 2.5527)
			(stroke
				(width 0.1524)
				(type default)
			)
			(layer "F.SilkS")
		)
		(fp_poly
			(pts
				(xy -2.669286 -2.982214) (xy -2.997454 -2.428494) (xy -3.294126 -2.982214)
			)
			(stroke
				(width 0)
				(type default)
			)
			(fill yes)
			(layer "F.SilkS")
		)
		(fp_line
			(start -2.249932 -2.549906)
			(end 2.249932 -2.549906)
			(stroke
				(width 0.1)
				(type default)
			)
			(layer "F.Fab")
		)
		(fp_line
			(start -2.249932 2.549906)
			(end -2.249932 -2.549906)
			(stroke
				(width 0.1)
				(type default)
			)
			(layer "F.Fab")
		)
		(fp_line
			(start 2.249932 -2.549906)
			(end 2.249932 2.549906)
			(stroke
				(width 0.1)
				(type default)
			)
			(layer "F.Fab")
		)
		(fp_line
			(start 2.249932 2.549906)
			(end -2.249932 2.549906)
			(stroke
				(width 0.1)
				(type default)
			)
			(layer "F.Fab")
		)
		(fp_poly
			(pts
				(xy -4.36372 -1.608328) (xy -4.36372 -2.233168) (xy -3.81 -1.905)
			)
			(stroke
				(width 0)
				(type default)
			)
			(fill yes)
			(layer "F.Fab")
		)
		(pad "1" smd rect
			(at -2.921 -1.949958 270)
			(size 0.3556 1.4986)
			(layers "F.Cu" "F.Mask" "F.Paste")
			(net "PD_JTAG_BMC_NTRST_N")
		)
		(pad "2" smd rect
			(at -2.921 -1.299972 270)
			(size 0.3556 1.4986)
			(layers "F.Cu" "F.Mask" "F.Paste")
			(net "FM_BMC_EN_DET")
		)
		(pad "3" smd rect
			(at -2.921 -0.649986 270)
			(size 0.3556 1.4986)
			(layers "F.Cu" "F.Mask" "F.Paste")
			(net "TP_JTAG_BMC_1B")
		)
		(pad "4" smd rect
			(at -2.921 0 270)
			(size 0.3556 1.4986)
			(layers "F.Cu" "F.Mask" "F.Paste")
			(net "JTAG_BMC_CPU_TCK")
		)
		(pad "5" smd rect
			(at -2.921 0.649986 270)
			(size 0.3556 1.4986)
			(layers "F.Cu" "F.Mask" "F.Paste")
			(net "FM_BMC_EN_DET")
		)
		(pad "6" smd rect
			(at -2.921 1.299972 270)
			(size 0.3556 1.4986)
			(layers "F.Cu" "F.Mask" "F.Paste")
			(net "JTAG_DBP_CPU_GTL_TCK_R1")
		)
		(pad "7" smd rect
			(at -2.921 1.949958 270)
			(size 0.3556 1.4986)
			(layers "F.Cu" "F.Mask" "F.Paste")
			(net "GND")
		)
		(pad "8" smd rect
			(at 2.921 1.949958 270)
			(size 0.3556 1.4986)
			(layers "F.Cu" "F.Mask" "F.Paste")
			(net "JTAG_DBP_TCK_PCH_R")
		)
		(pad "9" smd rect
			(at 2.921 1.299972 270)
			(size 0.3556 1.4986)
			(layers "F.Cu" "F.Mask" "F.Paste")
			(net "FM_BMC_EN_DET")
		)
		(pad "10" smd rect
			(at 2.921 0.649986 270)
			(size 0.3556 1.4986)
			(layers "F.Cu" "F.Mask" "F.Paste")
			(net "JTAG_BMC_PCH_TCK")
		)
		(pad "11" smd rect
			(at 2.921 0 270)
			(size 0.3556 1.4986)
			(layers "F.Cu" "F.Mask" "F.Paste")
			(net "TP_JTAG_BMC_4B")
		)
		(pad "12" smd rect
			(at 2.921 -0.649986 270)
			(size 0.3556 1.4986)
			(layers "F.Cu" "F.Mask" "F.Paste")
			(net "FM_BMC_EN_DET")
		)
		(pad "13" smd rect
			(at 2.921 -1.299972 270)
			(size 0.3556 1.4986)
			(layers "F.Cu" "F.Mask" "F.Paste")
			(net "PD_JTAG_BMC_NTRST_N")
		)
		(pad "14" smd rect
			(at 2.921 -1.949958 270)
			(size 0.3556 1.4986)
			(layers "F.Cu" "F.Mask" "F.Paste")
			(net "P3V3_AUX")
		)
	)
	(footprint ""
		(layer "F.Cu")
		(at 130.399028 -341.729822 90)
		(property "Reference" "PR1791"
			(at 0 0 90)
			(layer "F.SilkS")
			(hide yes)
			(effects
				(font
					(size 1.27 1.27)
				)
			)
		)
		(property "Value" ""
			(at 0 0 90)
			(layer "F.Fab")
			(effects
				(font
					(size 1.27 1.27)
				)
			)
		)
		(duplicate_pad_numbers_are_jumpers no)
		(fp_line
			(start 0.7874 -0.4064)
			(end 0.7874 0.4064)
			(stroke
				(width 0.1524)
				(type default)
			)
			(layer "F.SilkS")
		)
		(fp_line
			(start -0.7874 -0.4064)
			(end 0.7874 -0.4064)
			(stroke
				(width 0.1524)
				(type default)
			)
			(layer "F.SilkS")
		)
		(fp_line
			(start 0.7874 0.4064)
			(end -0.7874 0.4064)
			(stroke
				(width 0.1524)
				(type default)
			)
			(layer "F.SilkS")
		)
		(fp_line
			(start -0.7874 0.4064)
			(end -0.7874 -0.4064)
			(stroke
				(width 0.1524)
				(type default)
			)
			(layer "F.SilkS")
		)
		(fp_line
			(start -0.12065 -0.305054)
			(end -0.12065 -0.2794)
			(stroke
				(width 0.1)
				(type default)
			)
			(layer "F.Fab")
		)
		(fp_line
			(start -0.67945 -0.305054)
			(end -0.12065 -0.305054)
			(stroke
				(width 0.1)
				(type default)
			)
			(layer "F.Fab")
		)
		(fp_line
			(start 0.67945 -0.3048)
			(end 0.67945 0.3048)
			(stroke
				(width 0.1)
				(type default)
			)
			(layer "F.Fab")
		)
		(fp_line
			(start 0.12065 -0.3048)
			(end 0.67945 -0.3048)
			(stroke
				(width 0.1)
				(type default)
			)
			(layer "F.Fab")
		)
		(fp_line
			(start 0.12065 -0.2794)
			(end 0.12065 -0.3048)
			(stroke
				(width 0.1)
				(type default)
			)
			(layer "F.Fab")
		)
		(fp_line
			(start -0.12065 -0.2794)
			(end 0.12065 -0.2794)
			(stroke
				(width 0.1)
				(type default)
			)
			(layer "F.Fab")
		)
		(fp_line
			(start 0.120396 0.2794)
			(end -0.12065 0.2794)
			(stroke
				(width 0.1)
				(type default)
			)
			(layer "F.Fab")
		)
		(fp_line
			(start -0.12065 0.2794)
			(end -0.12065 0.3048)
			(stroke
				(width 0.1)
				(type default)
			)
			(layer "F.Fab")
		)
		(fp_line
			(start 0.67945 0.3048)
			(end 0.120396 0.3048)
			(stroke
				(width 0.1)
				(type default)
			)
			(layer "F.Fab")
		)
		(fp_line
			(start 0.120396 0.3048)
			(end 0.120396 0.2794)
			(stroke
				(width 0.1)
				(type default)
			)
			(layer "F.Fab")
		)
		(fp_line
			(start -0.12065 0.3048)
			(end -0.67945 0.3048)
			(stroke
				(width 0.1)
				(type default)
			)
			(layer "F.Fab")
		)
		(fp_line
			(start -0.67945 0.3048)
			(end -0.67945 -0.305054)
			(stroke
				(width 0.1)
				(type default)
			)
			(layer "F.Fab")
		)
		(pad "1" smd circle
			(at -0.40005 0 90)
			(size 0 0)
			(layers "F.Cu" "F.Mask" "F.Paste")
			(net "SW_PVCCIN_CPU1_BOOT5")
		)
		(pad "2" smd circle
			(at 0.40005 0 90)
			(size 0 0)
			(layers "F.Cu" "F.Mask" "F.Paste")
			(net "SW_PVCCIN_CPU1_BOOT5_R")
		)
	)
	(footprint ""
		(layer "F.Cu")
		(at 226.733608 -399.743422 180)
		(property "Reference" "PC2349"
			(at 0 0 180)
			(layer "F.SilkS")
			(hide yes)
			(effects
				(font
					(size 1.27 1.27)
				)
			)
		)
		(property "Value" ""
			(at 0 0 180)
			(layer "F.Fab")
			(effects
				(font
					(size 1.27 1.27)
				)
			)
		)
		(duplicate_pad_numbers_are_jumpers no)
		(fp_line
			(start 0.7874 0.4064)
			(end -0.7874 0.4064)
			(stroke
				(width 0.1524)
				(type default)
			)
			(layer "F.SilkS")
		)
		(fp_line
			(start 0.7874 -0.4064)
			(end 0.7874 0.4064)
			(stroke
				(width 0.1524)
				(type default)
			)
			(layer "F.SilkS")
		)
		(fp_line
			(start -0.7874 0.4064)
			(end -0.7874 -0.4064)
			(stroke
				(width 0.1524)
				(type default)
			)
			(layer "F.SilkS")
		)
		(fp_line
			(start -0.7874 -0.4064)
			(end 0.7874 -0.4064)
			(stroke
				(width 0.1524)
				(type default)
			)
			(layer "F.SilkS")
		)
		(fp_line
			(start 0.67945 0.3048)
			(end 0.120396 0.3048)
			(stroke
				(width 0.1)
				(type default)
			)
			(layer "F.Fab")
		)
		(fp_line
			(start 0.67945 -0.3048)
			(end 0.67945 0.3048)
			(stroke
				(width 0.1)
				(type default)
			)
			(layer "F.Fab")
		)
		(fp_line
			(start 0.12065 -0.2794)
			(end 0.12065 -0.3048)
			(stroke
				(width 0.1)
				(type default)
			)
			(layer "F.Fab")
		)
		(fp_line
			(start 0.12065 -0.3048)
			(end 0.67945 -0.3048)
			(stroke
				(width 0.1)
				(type default)
			)
			(layer "F.Fab")
		)
		(fp_line
			(start 0.120396 0.3048)
			(end 0.120396 0.2794)
			(stroke
				(width 0.1)
				(type default)
			)
			(layer "F.Fab")
		)
		(fp_line
			(start 0.120396 0.2794)
			(end -0.12065 0.2794)
			(stroke
				(width 0.1)
				(type default)
			)
			(layer "F.Fab")
		)
		(fp_line
			(start -0.12065 0.3048)
			(end -0.67945 0.3048)
			(stroke
				(width 0.1)
				(type default)
			)
			(layer "F.Fab")
		)
		(fp_line
			(start -0.12065 0.2794)
			(end -0.12065 0.3048)
			(stroke
				(width 0.1)
				(type default)
			)
			(layer "F.Fab")
		)
		(fp_line
			(start -0.12065 -0.2794)
			(end 0.12065 -0.2794)
			(stroke
				(width 0.1)
				(type default)
			)
			(layer "F.Fab")
		)
		(fp_line
			(start -0.12065 -0.305054)
			(end -0.12065 -0.2794)
			(stroke
				(width 0.1)
				(type default)
			)
			(layer "F.Fab")
		)
		(fp_line
			(start -0.67945 0.3048)
			(end -0.67945 -0.305054)
			(stroke
				(width 0.1)
				(type default)
			)
			(layer "F.Fab")
		)
		(fp_line
			(start -0.67945 -0.305054)
			(end -0.12065 -0.305054)
			(stroke
				(width 0.1)
				(type default)
			)
			(layer "F.Fab")
		)
		(pad "1" smd circle
			(at -0.40005 0 180)
			(size 0 0)
			(layers "F.Cu" "F.Mask" "F.Paste")
			(net "HSC_OCREF")
		)
		(pad "2" smd circle
			(at 0.40005 0 180)
			(size 0 0)
			(layers "F.Cu" "F.Mask" "F.Paste")
			(net "AGND_HSC")
		)
	)
	(footprint ""
		(layer "F.Cu")
		(at 141.572234 -402.371052 -90)
		(property "Reference" "C757"
			(at 0 0 270)
			(layer "F.SilkS")
			(hide yes)
			(effects
				(font
					(size 1.27 1.27)
				)
			)
		)
		(property "Value" ""
			(at 0 0 270)
			(layer "F.Fab")
			(effects
				(font
					(size 1.27 1.27)
				)
			)
		)
		(duplicate_pad_numbers_are_jumpers no)
		(fp_line
			(start -0.299974 0.150114)
			(end -0.299974 -0.150114)
			(stroke
				(width 0.1)
				(type default)
			)
			(layer "F.Fab")
		)
		(fp_line
			(start 0.299974 0.150114)
			(end -0.299974 0.150114)
			(stroke
				(width 0.1)
				(type default)
			)
			(layer "F.Fab")
		)
		(fp_line
			(start -0.299974 -0.150114)
			(end 0.299974 -0.150114)
			(stroke
				(width 0.1)
				(type default)
			)
			(layer "F.Fab")
		)
		(fp_line
			(start 0.299974 -0.150114)
			(end 0.299974 0.150114)
			(stroke
				(width 0.1)
				(type default)
			)
			(layer "F.Fab")
		)
		(pad "1" smd rect
			(at -0.2667 0 270)
			(size 0.3048 0.381)
			(layers "F.Cu" "F.Mask" "F.Paste")
			(net "P5E_CPU1_PE2_TX_C_DP<8>")
		)
		(pad "2" smd rect
			(at 0.2667 0 270)
			(size 0.3048 0.381)
			(layers "F.Cu" "F.Mask" "F.Paste")
			(net "P5E_CPU1_PE2_TX_DP<8>")
		)
	)
	(footprint ""
		(layer "F.Cu")
		(at 420.473632 -178.762914)
		(property "Reference" "PR1775"
			(at 0 0 0)
			(layer "F.SilkS")
			(hide yes)
			(effects
				(font
					(size 1.27 1.27)
				)
			)
		)
		(property "Value" ""
			(at 0 0 0)
			(layer "F.Fab")
			(effects
				(font
					(size 1.27 1.27)
				)
			)
		)
		(duplicate_pad_numbers_are_jumpers no)
		(fp_line
			(start -0.7874 -0.4064)
			(end 0.7874 -0.4064)
			(stroke
				(width 0.1524)
				(type default)
			)
			(layer "F.SilkS")
		)
		(fp_line
			(start -0.7874 0.4064)
			(end -0.7874 -0.4064)
			(stroke
				(width 0.1524)
				(type default)
			)
			(layer "F.SilkS")
		)
		(fp_line
			(start 0.7874 -0.4064)
			(end 0.7874 0.4064)
			(stroke
				(width 0.1524)
				(type default)
			)
			(layer "F.SilkS")
		)
		(fp_line
			(start 0.7874 0.4064)
			(end -0.7874 0.4064)
			(stroke
				(width 0.1524)
				(type default)
			)
			(layer "F.SilkS")
		)
		(fp_line
			(start -0.67945 -0.305054)
			(end -0.12065 -0.305054)
			(stroke
				(width 0.1)
				(type default)
			)
			(layer "F.Fab")
		)
		(fp_line
			(start -0.67945 0.3048)
			(end -0.67945 -0.305054)
			(stroke
				(width 0.1)
				(type default)
			)
			(layer "F.Fab")
		)
		(fp_line
			(start -0.12065 -0.305054)
			(end -0.12065 -0.2794)
			(stroke
				(width 0.1)
				(type default)
			)
			(layer "F.Fab")
		)
		(fp_line
			(start -0.12065 -0.2794)
			(end 0.12065 -0.2794)
			(stroke
				(width 0.1)
				(type default)
			)
			(layer "F.Fab")
		)
		(fp_line
			(start -0.12065 0.2794)
			(end -0.12065 0.3048)
			(stroke
				(width 0.1)
				(type default)
			)
			(layer "F.Fab")
		)
		(fp_line
			(start -0.12065 0.3048)
			(end -0.67945 0.3048)
			(stroke
				(width 0.1)
				(type default)
			)
			(layer "F.Fab")
		)
		(fp_line
			(start 0.120396 0.2794)
			(end -0.12065 0.2794)
			(stroke
				(width 0.1)
				(type default)
			)
			(layer "F.Fab")
		)
		(fp_line
			(start 0.120396 0.3048)
			(end 0.120396 0.2794)
			(stroke
				(width 0.1)
				(type default)
			)
			(layer "F.Fab")
		)
		(fp_line
			(start 0.12065 -0.3048)
			(end 0.67945 -0.3048)
			(stroke
				(width 0.1)
				(type default)
			)
			(layer "F.Fab")
		)
		(fp_line
			(start 0.12065 -0.2794)
			(end 0.12065 -0.3048)
			(stroke
				(width 0.1)
				(type default)
			)
			(layer "F.Fab")
		)
		(fp_line
			(start 0.67945 -0.3048)
			(end 0.67945 0.3048)
			(stroke
				(width 0.1)
				(type default)
			)
			(layer "F.Fab")
		)
		(fp_line
			(start 0.67945 0.3048)
			(end 0.120396 0.3048)
			(stroke
				(width 0.1)
				(type default)
			)
			(layer "F.Fab")
		)
		(pad "1" smd circle
			(at -0.40005 0)
			(size 0 0)
			(layers "F.Cu" "F.Mask" "F.Paste")
			(net "SW_PVCCINFAON_CPU0_BOOT2")
		)
		(pad "2" smd circle
			(at 0.40005 0)
			(size 0 0)
			(layers "F.Cu" "F.Mask" "F.Paste")
			(net "SW_PVCCINFAON_CPU0_BOOT2_R")
		)
	)
)
